(kicad_pcb
	(version 20260206)
	(generator "pcbnew")
	(generator_version "10.0")
	(general
		(thickness 1.6)
		(legacy_teardrops no)
	)
	(paper "A4")
	(title_block
		(title "dpb — 14545-sa.0730WZS0815.brd")
		(comment 1 "Honey Badger (Wiwynn) / footprints 155-159 of 1066")
	)
	(layers
		(0 "F.Cu" signal "TOP")
		(4 "In1.Cu" signal "L2GND")
		(6 "In2.Cu" signal "L3")
		(8 "In3.Cu" signal "L4VCC")
		(10 "In4.Cu" signal "L5VCC")
		(12 "In5.Cu" signal "L6")
		(14 "In6.Cu" signal "L7GND")
		(2 "B.Cu" signal "BOTTOM")
		(9 "F.Adhes" user "F.Adhesive")
		(11 "B.Adhes" user "B.Adhesive")
		(13 "F.Paste" user "Package Geometry/Pastemask Top")
		(15 "B.Paste" user "Package Geometry/Pastemask Bottom")
		(5 "F.SilkS" user "Ref Des/Silkscreen Top")
		(7 "B.SilkS" user "Ref Des/Silkscreen Bottom")
		(1 "F.Mask" user "Board Geometry/Soldermask Top")
		(3 "B.Mask" user "Board Geometry/Soldermask Bottom")
		(17 "Dwgs.User" user "User.Drawings")
		(19 "Cmts.User" user "User.Comments")
		(21 "Eco1.User" user "User.Eco1")
		(23 "Eco2.User" user "User.Eco2")
		(25 "Edge.Cuts" user "Board Geometry/Outline")
		(27 "Margin" user)
		(31 "F.CrtYd" user "Package Geometry/Place Bound Top")
		(29 "B.CrtYd" user "Package Geometry/Place Bound Bottom")
		(35 "F.Fab" user "Ref Des/Assembly Top")
		(33 "B.Fab" user "Ref Des/Assembly Bottom")
	)
	(footprint ""
		(layer "F.Cu")
		(at 33.893252 -160.03651 -90)
		(property "Reference" "C230"
			(at 0 0 270)
			(layer "F.SilkS")
			(hide yes)
			(effects
				(font
					(size 1.27 1.27)
				)
			)
		)
		(property "Value" "SCD01U50V2KX-1GP"
			(at 1.1811 -2.7051 270)
			(unlocked yes)
			(layer "F.Fab")
			(hide yes)
			(effects
				(font
					(size 1.016 1.016)
					(thickness 0.1524)
				)
			)
		)
		(property "Device Type" "C402H22"
			(at 1.1811 -4.2291 270)
			(unlocked yes)
			(layer "F.Fab")
			(hide yes)
			(effects
				(font
					(size 1.016 1.016)
					(thickness 0.1524)
				)
			)
		)
		(duplicate_pad_numbers_are_jumpers no)
		(fp_rect
			(start -0.4318 0.9525)
			(end 0.4318 -0.9525)
			(stroke
				(width 0)
				(type default)
			)
			(fill no)
			(layer "F.CrtYd")
		)
		(fp_rect
			(start -0.4318 0.9525)
			(end 0.4318 -0.9525)
			(stroke
				(width 0)
				(type default)
			)
			(fill no)
			(layer "F.Fab")
		)
		(pad "1" smd custom
			(at 0 -0.4445 270)
			(size 0.1524 0.1524)
			(layers "F.Cu" "F.Mask" "F.Paste")
			(net "SAS2X28_DRIVE_RX_N_A8")
			(options
				(clearance outline)
				(anchor circle)
			)
			(primitives
				(gr_poly
					(pts
						(arc
							(start 0.3048 -0.2032)
							(mid 0.275042 -0.275042)
							(end 0.2032 -0.3048)
						)
						(arc
							(start -0.2032 -0.3048)
							(mid -0.275042 -0.275042)
							(end -0.3048 -0.2032)
						)
						(arc
							(start -0.3048 0.2032)
							(mid -0.275042 0.275042)
							(end -0.2032 0.3048)
						)
						(arc
							(start 0.2032 0.3048)
							(mid 0.275042 0.275042)
							(end 0.3048 0.2032)
						)
					)
					(width 0)
					(fill yes)
				)
			)
		)
		(pad "2" smd custom
			(at 0 0.4445 270)
			(size 0.1524 0.1524)
			(layers "F.Cu" "F.Mask" "F.Paste")
			(net "SAS2X28_A_HDD8_RX_-")
			(options
				(clearance outline)
				(anchor circle)
			)
			(primitives
				(gr_poly
					(pts
						(arc
							(start 0.3048 -0.2032)
							(mid 0.275042 -0.275042)
							(end 0.2032 -0.3048)
						)
						(arc
							(start -0.2032 -0.3048)
							(mid -0.275042 -0.275042)
							(end -0.3048 -0.2032)
						)
						(arc
							(start -0.3048 0.2032)
							(mid -0.275042 0.275042)
							(end -0.2032 0.3048)
						)
						(arc
							(start 0.2032 0.3048)
							(mid 0.275042 0.275042)
							(end 0.3048 0.2032)
						)
					)
					(width 0)
					(fill yes)
				)
			)
		)
	)
	(footprint ""
		(layer "F.Cu")
		(at 48.335946 -452.755 90)
		(property "Reference" "Q39"
			(at 0 0 90)
			(layer "F.SilkS")
			(hide yes)
			(effects
				(font
					(size 1.27 1.27)
				)
			)
		)
		(property "Value" "PMBS3904-1-GP"
			(at 0 -9.0932 90)
			(unlocked yes)
			(layer "F.Fab")
			(hide yes)
			(effects
				(font
					(size 1.016 1.016)
					(thickness 0.1524)
				)
			)
		)
		(property "Device Type" "SOT-23-10H44"
			(at 0 -10.6172 90)
			(unlocked yes)
			(layer "F.Fab")
			(hide yes)
			(effects
				(font
					(size 1.016 1.016)
					(thickness 0.1524)
				)
			)
		)
		(duplicate_pad_numbers_are_jumpers no)
		(fp_line
			(start 1.651 -1.778)
			(end -1.651 -1.778)
			(stroke
				(width 0.1524)
				(type default)
			)
			(layer "F.SilkS")
		)
		(fp_line
			(start -1.651 -1.778)
			(end -1.651 1.778)
			(stroke
				(width 0.1524)
				(type default)
			)
			(layer "F.SilkS")
		)
		(fp_line
			(start 1.651 1.778)
			(end 1.651 -1.778)
			(stroke
				(width 0.1524)
				(type default)
			)
			(layer "F.SilkS")
		)
		(fp_line
			(start -1.651 1.778)
			(end 1.651 1.778)
			(stroke
				(width 0.1524)
				(type default)
			)
			(layer "F.SilkS")
		)
		(fp_line
			(start -0.9906 1.86309)
			(end -0.701294 2.15265)
			(stroke
				(width 0.0127)
				(type default)
			)
			(layer "F.SilkS")
		)
		(fp_line
			(start -0.994156 1.8669)
			(end -0.987044 1.8669)
			(stroke
				(width 0.0127)
				(type default)
			)
			(layer "F.SilkS")
		)
		(fp_line
			(start -1.003808 1.876552)
			(end -0.977646 1.876552)
			(stroke
				(width 0.0127)
				(type default)
			)
			(layer "F.SilkS")
		)
		(fp_line
			(start -0.635 1.8796)
			(end -1.7526 1.8796)
			(stroke
				(width 0.3302)
				(type default)
			)
			(layer "F.SilkS")
		)
		(fp_line
			(start -1.7526 1.8796)
			(end -1.7526 0.9906)
			(stroke
				(width 0.3302)
				(type default)
			)
			(layer "F.SilkS")
		)
		(fp_line
			(start -1.013206 1.88595)
			(end -0.967994 1.88595)
			(stroke
				(width 0.0127)
				(type default)
			)
			(layer "F.SilkS")
		)
		(fp_line
			(start -1.022858 1.895602)
			(end -0.958596 1.895602)
			(stroke
				(width 0.0127)
				(type default)
			)
			(layer "F.SilkS")
		)
		(fp_line
			(start -1.032256 1.905)
			(end -0.948944 1.905)
			(stroke
				(width 0.0127)
				(type default)
			)
			(layer "F.SilkS")
		)
		(fp_line
			(start -1.041908 1.914652)
			(end -0.939546 1.914652)
			(stroke
				(width 0.0127)
				(type default)
			)
			(layer "F.SilkS")
		)
		(fp_line
			(start -1.051306 1.92405)
			(end -0.929894 1.92405)
			(stroke
				(width 0.0127)
				(type default)
			)
			(layer "F.SilkS")
		)
		(fp_line
			(start -1.060958 1.933702)
			(end -0.920496 1.933702)
			(stroke
				(width 0.0127)
				(type default)
			)
			(layer "F.SilkS")
		)
		(fp_line
			(start -1.070356 1.9431)
			(end -0.910844 1.9431)
			(stroke
				(width 0.0127)
				(type default)
			)
			(layer "F.SilkS")
		)
		(fp_line
			(start -1.080008 1.952752)
			(end -0.901446 1.952752)
			(stroke
				(width 0.0127)
				(type default)
			)
			(layer "F.SilkS")
		)
		(fp_line
			(start -1.089406 1.96215)
			(end -0.891794 1.96215)
			(stroke
				(width 0.0127)
				(type default)
			)
			(layer "F.SilkS")
		)
		(fp_line
			(start -1.099058 1.971802)
			(end -0.882396 1.971802)
			(stroke
				(width 0.0127)
				(type default)
			)
			(layer "F.SilkS")
		)
		(fp_line
			(start -1.108456 1.9812)
			(end -0.872744 1.9812)
			(stroke
				(width 0.0127)
				(type default)
			)
			(layer "F.SilkS")
		)
		(fp_line
			(start -1.118108 1.990852)
			(end -0.863346 1.990852)
			(stroke
				(width 0.0127)
				(type default)
			)
			(layer "F.SilkS")
		)
		(fp_line
			(start -1.127506 2.00025)
			(end -0.853694 2.00025)
			(stroke
				(width 0.0127)
				(type default)
			)
			(layer "F.SilkS")
		)
		(fp_line
			(start -1.137158 2.009902)
			(end -0.844296 2.009902)
			(stroke
				(width 0.0127)
				(type default)
			)
			(layer "F.SilkS")
		)
		(fp_line
			(start -1.146556 2.0193)
			(end -0.834644 2.0193)
			(stroke
				(width 0.0127)
				(type default)
			)
			(layer "F.SilkS")
		)
		(fp_line
			(start -1.156208 2.028952)
			(end -0.825246 2.028952)
			(stroke
				(width 0.0127)
				(type default)
			)
			(layer "F.SilkS")
		)
		(fp_line
			(start -1.165606 2.03835)
			(end -0.815594 2.03835)
			(stroke
				(width 0.0127)
				(type default)
			)
			(layer "F.SilkS")
		)
		(fp_line
			(start -1.175258 2.048002)
			(end -0.806196 2.048002)
			(stroke
				(width 0.0127)
				(type default)
			)
			(layer "F.SilkS")
		)
		(fp_line
			(start -1.184656 2.0574)
			(end -0.796544 2.0574)
			(stroke
				(width 0.0127)
				(type default)
			)
			(layer "F.SilkS")
		)
		(fp_line
			(start -1.194308 2.067052)
			(end -0.787146 2.067052)
			(stroke
				(width 0.0127)
				(type default)
			)
			(layer "F.SilkS")
		)
		(fp_line
			(start -1.203706 2.07645)
			(end -0.777494 2.07645)
			(stroke
				(width 0.0127)
				(type default)
			)
			(layer "F.SilkS")
		)
		(fp_line
			(start -1.213358 2.086102)
			(end -0.768096 2.086102)
			(stroke
				(width 0.0127)
				(type default)
			)
			(layer "F.SilkS")
		)
		(fp_line
			(start -1.222756 2.0955)
			(end -0.758444 2.0955)
			(stroke
				(width 0.0127)
				(type default)
			)
			(layer "F.SilkS")
		)
		(fp_line
			(start -1.232408 2.105152)
			(end -0.749046 2.105152)
			(stroke
				(width 0.0127)
				(type default)
			)
			(layer "F.SilkS")
		)
		(fp_line
			(start -1.241806 2.11455)
			(end -0.739394 2.11455)
			(stroke
				(width 0.0127)
				(type default)
			)
			(layer "F.SilkS")
		)
		(fp_line
			(start -1.251458 2.124202)
			(end -0.729996 2.124202)
			(stroke
				(width 0.0127)
				(type default)
			)
			(layer "F.SilkS")
		)
		(fp_line
			(start -1.260856 2.1336)
			(end -0.720344 2.1336)
			(stroke
				(width 0.0127)
				(type default)
			)
			(layer "F.SilkS")
		)
		(fp_line
			(start -0.719074 2.145538)
			(end -1.265936 2.14122)
			(stroke
				(width 0.0127)
				(type default)
			)
			(layer "F.SilkS")
		)
		(fp_line
			(start -1.279398 2.152142)
			(end -0.9906 1.86309)
			(stroke
				(width 0.0127)
				(type default)
			)
			(layer "F.SilkS")
		)
		(fp_line
			(start -0.71628 2.15265)
			(end -1.26492 2.15265)
			(stroke
				(width 0.0127)
				(type default)
			)
			(layer "F.SilkS")
		)
		(fp_line
			(start -1.279144 2.15265)
			(end -0.701294 2.15265)
			(stroke
				(width 0.0127)
				(type default)
			)
			(layer "F.SilkS")
		)
		(fp_poly
			(pts
				(xy -1.285748 2.159) (xy -1.285748 1.8796) (xy -1.778 1.8796) (xy -1.778 -1.8796) (xy 1.778 -1.8796)
				(xy 1.778 1.8796) (xy -0.694944 1.8796) (xy -0.694944 2.159)
			)
			(stroke
				(width 0)
				(type default)
			)
			(fill no)
			(layer "F.CrtYd")
		)
		(fp_poly
			(pts
				(xy -1.285748 2.159) (xy -1.285748 1.8796) (xy -1.778 1.8796) (xy -1.778 -1.8796) (xy 1.778 -1.8796)
				(xy 1.778 1.8796) (xy -0.694944 1.8796) (xy -0.694944 2.159)
			)
			(stroke
				(width 0)
				(type default)
			)
			(fill no)
			(layer "F.Fab")
		)
		(pad "1" smd rect
			(at -0.98425 0.9525 90)
			(size 0.762 1.143)
			(layers "F.Cu" "F.Mask" "F.Paste")
			(net "FLT_HDD5_B")
		)
		(pad "2" smd rect
			(at 0.98425 0.9525 90)
			(size 0.762 1.143)
			(layers "F.Cu" "F.Mask" "F.Paste")
			(net "GND")
		)
		(pad "3" smd rect
			(at 0 -0.9525 90)
			(size 0.762 1.143)
			(layers "F.Cu" "F.Mask" "F.Paste")
			(net "DRIVE_ACT_5")
		)
	)
	(footprint ""
		(layer "F.Cu")
		(at 218.142058 -365.962184 -90)
		(property "Reference" "C118"
			(at 0 0 270)
			(layer "F.SilkS")
			(hide yes)
			(effects
				(font
					(size 1.27 1.27)
				)
			)
		)
		(property "Value" "SCD01U50V2KX-1GP"
			(at 1.1811 -2.7051 270)
			(unlocked yes)
			(layer "F.Fab")
			(hide yes)
			(effects
				(font
					(size 1.016 1.016)
					(thickness 0.1524)
				)
			)
		)
		(property "Device Type" "C402H22"
			(at 1.1811 -4.2291 270)
			(unlocked yes)
			(layer "F.Fab")
			(hide yes)
			(effects
				(font
					(size 1.016 1.016)
					(thickness 0.1524)
				)
			)
		)
		(duplicate_pad_numbers_are_jumpers no)
		(fp_rect
			(start -0.4318 0.9525)
			(end 0.4318 -0.9525)
			(stroke
				(width 0)
				(type default)
			)
			(fill no)
			(layer "F.CrtYd")
		)
		(fp_rect
			(start -0.4318 0.9525)
			(end 0.4318 -0.9525)
			(stroke
				(width 0)
				(type default)
			)
			(fill no)
			(layer "F.Fab")
		)
		(pad "1" smd custom
			(at 0 -0.4445 270)
			(size 0.1524 0.1524)
			(layers "F.Cu" "F.Mask" "F.Paste")
			(net "SAS2X28_DRIVE_RX_N_A1")
			(options
				(clearance outline)
				(anchor circle)
			)
			(primitives
				(gr_poly
					(pts
						(arc
							(start 0.3048 -0.2032)
							(mid 0.275042 -0.275042)
							(end 0.2032 -0.3048)
						)
						(arc
							(start -0.2032 -0.3048)
							(mid -0.275042 -0.275042)
							(end -0.3048 -0.2032)
						)
						(arc
							(start -0.3048 0.2032)
							(mid -0.275042 0.275042)
							(end -0.2032 0.3048)
						)
						(arc
							(start 0.2032 0.3048)
							(mid 0.275042 0.275042)
							(end 0.3048 0.2032)
						)
					)
					(width 0)
					(fill yes)
				)
			)
		)
		(pad "2" smd custom
			(at 0 0.4445 270)
			(size 0.1524 0.1524)
			(layers "F.Cu" "F.Mask" "F.Paste")
			(net "SAS2X28_A_HDD1_RX_-")
			(options
				(clearance outline)
				(anchor circle)
			)
			(primitives
				(gr_poly
					(pts
						(arc
							(start 0.3048 -0.2032)
							(mid 0.275042 -0.275042)
							(end 0.2032 -0.3048)
						)
						(arc
							(start -0.2032 -0.3048)
							(mid -0.275042 -0.275042)
							(end -0.3048 -0.2032)
						)
						(arc
							(start -0.3048 0.2032)
							(mid -0.275042 0.275042)
							(end -0.2032 0.3048)
						)
						(arc
							(start 0.2032 0.3048)
							(mid 0.275042 0.275042)
							(end 0.3048 0.2032)
						)
					)
					(width 0)
					(fill yes)
				)
			)
		)
	)
	(footprint ""
		(layer "F.Cu")
		(at 8.127746 -501.4087)
		(property "Reference" "PR42"
			(at 0 0 0)
			(layer "F.SilkS")
			(hide yes)
			(effects
				(font
					(size 1.27 1.27)
				)
			)
		)
		(property "Value" "100KR2F-L1-GP"
			(at 0.064008 -3.993896 0)
			(unlocked yes)
			(layer "F.Fab")
			(hide yes)
			(effects
				(font
					(size 1.016 1.016)
					(thickness 0.1524)
				)
			)
		)
		(property "Device Type" "R402H16"
			(at 0.064008 -5.517896 0)
			(unlocked yes)
			(layer "F.Fab")
			(hide yes)
			(effects
				(font
					(size 1.016 1.016)
					(thickness 0.1524)
				)
			)
		)
		(duplicate_pad_numbers_are_jumpers no)
		(fp_line
			(start -0.508 -0.9398)
			(end -0.508 0.9398)
			(stroke
				(width 0.1524)
				(type default)
			)
			(layer "F.SilkS")
		)
		(fp_line
			(start 0.508 -0.9398)
			(end -0.508 -0.9398)
			(stroke
				(width 0.1524)
				(type default)
			)
			(layer "F.SilkS")
		)
		(fp_rect
			(start -0.508 0.9398)
			(end 0.508 -0.9398)
			(stroke
				(width 0)
				(type default)
			)
			(fill no)
			(layer "F.CrtYd")
		)
		(fp_rect
			(start -0.508 0.9398)
			(end 0.508 -0.9398)
			(stroke
				(width 0)
				(type default)
			)
			(fill no)
			(layer "F.Fab")
		)
		(pad "1" smd custom
			(at 0 -0.4445)
			(size 0.1397 0.1397)
			(layers "F.Cu" "F.Mask" "F.Paste")
			(net "P5VC_PGD")
			(options
				(clearance outline)
				(anchor circle)
			)
			(primitives
				(gr_poly
					(pts
						(arc
							(start -0.1778 -0.2794)
							(mid -0.249642 -0.249642)
							(end -0.2794 -0.1778)
						)
						(arc
							(start -0.2794 0.1778)
							(mid -0.249642 0.249642)
							(end -0.1778 0.2794)
						)
						(arc
							(start 0.1778 0.2794)
							(mid 0.249642 0.249642)
							(end 0.2794 0.1778)
						)
						(arc
							(start 0.2794 -0.1778)
							(mid 0.249642 -0.249642)
							(end 0.1778 -0.2794)
						)
					)
					(width 0)
					(fill yes)
				)
			)
		)
		(pad "2" smd custom
			(at 0 0.4445)
			(size 0.1397 0.1397)
			(layers "F.Cu" "F.Mask" "F.Paste")
			(net "P5VC_MODE_PG")
			(options
				(clearance outline)
				(anchor circle)
			)
			(primitives
				(gr_poly
					(pts
						(arc
							(start -0.1778 -0.2794)
							(mid -0.249642 -0.249642)
							(end -0.2794 -0.1778)
						)
						(arc
							(start -0.2794 0.1778)
							(mid -0.249642 0.249642)
							(end -0.1778 0.2794)
						)
						(arc
							(start 0.1778 0.2794)
							(mid 0.249642 0.249642)
							(end 0.2794 0.1778)
						)
						(arc
							(start 0.2794 -0.1778)
							(mid 0.249642 -0.249642)
							(end 0.1778 -0.2794)
						)
					)
					(width 0)
					(fill yes)
				)
			)
		)
	)
	(footprint ""
		(layer "F.Cu")
		(at 58.038492 -75.339956 90)
		(property "Reference" "R234"
			(at 0 0 90)
			(layer "F.SilkS")
			(hide yes)
			(effects
				(font
					(size 1.27 1.27)
				)
			)
		)
		(property "Value" "2R2010J-1-GP"
			(at 0.254 -8.0772 90)
			(unlocked yes)
			(layer "F.Fab")
			(hide yes)
			(effects
				(font
					(size 1.016 1.016)
					(thickness 0.1524)
				)
			)
		)
		(property "Device Type" "R2010H28"
			(at 0.254 -9.6774 90)
			(unlocked yes)
			(layer "F.Fab")
			(hide yes)
			(effects
				(font
					(size 1.016 1.016)
					(thickness 0.1524)
				)
			)
		)
		(duplicate_pad_numbers_are_jumpers no)
		(fp_line
			(start 1.651 -3.302)
			(end -1.651 -3.302)
			(stroke
				(width 0.1524)
				(type default)
			)
			(layer "F.SilkS")
		)
		(fp_line
			(start -1.651 -3.302)
			(end -1.651 3.302)
			(stroke
				(width 0.1524)
				(type default)
			)
			(layer "F.SilkS")
		)
		(fp_line
			(start 1.651 3.302)
			(end 1.651 -3.302)
			(stroke
				(width 0.1524)
				(type default)
			)
			(layer "F.SilkS")
		)
		(fp_line
			(start -1.651 3.302)
			(end 1.651 3.302)
			(stroke
				(width 0.1524)
				(type default)
			)
			(layer "F.SilkS")
		)
		(fp_rect
			(start -1.7272 -3.3782)
			(end 1.7272 3.3782)
			(stroke
				(width 0)
				(type default)
			)
			(fill no)
			(layer "F.CrtYd")
		)
		(fp_poly
			(pts
				(xy 1.7272 3.3782) (xy 1.7272 -3.3782) (xy -1.7272 -3.3782) (xy -1.7272 3.3782)
			)
			(stroke
				(width 0)
				(type default)
			)
			(fill no)
			(layer "F.Fab")
		)
		(pad "1" smd rect
			(at 0 -2.3495 90)
			(size 2.794 1.143)
			(layers "F.Cu" "F.Mask" "F.Paste")
			(net "5V_PRE_9")
		)
		(pad "2" smd rect
			(at 0 2.3495 90)
			(size 2.794 1.143)
			(layers "F.Cu" "F.Mask" "F.Paste")
			(net "P5V_HDD9")
		)
	)
)
